# T6G (Grand Teton) — schematic netlist excerpt (pin names and nets, part order shuffled) for the footprints in the layout excerpt that follows; sources: Cadence DE-HDL packaged netlist, KiCad conversion of 04192023_DAF0TMB3IC0_F0TG_MB_C_brd_V02_OCP.brd

PC6026  Q_CAP  22UF 4V 20% X6S  pkg C0805  page 270 : A = P1V2_AUX ; B = GND
C2585  Q_CAP  22UF 4V 20% X6S  pkg C0402  page 70 : A = PVDDCR_SOC_P0 ; B = GND
C382  Q_CAP  1UF 4V 20% X6S  pkg 0201  page 345 : A = P0V9_CPU1_RT2_2A ; B = GND

(kicad_pcb
	(version 20260206)
	(generator "pcbnew")
	(generator_version "10.0")
	(general
		(thickness 1.6)
		(legacy_teardrops no)
	)
	(paper "A4")
	(title_block
		(title "04192023_DAF0TMB3IC0_F0TG_MB_C_brd_V02_OCP.brd")
		(comment 1 "Grand Teton / footprints 8114-8116 of 8354")
	)
	(layers
		(0 "F.Cu" signal "TOP")
		(4 "In1.Cu" signal "GND")
		(6 "In2.Cu" signal "IN1")
		(8 "In3.Cu" signal "GND1")
		(10 "In4.Cu" signal "IN2")
		(12 "In5.Cu" signal "GND2")
		(14 "In6.Cu" signal "IN3")
		(16 "In7.Cu" signal "GND3")
		(18 "In8.Cu" signal "VCC")
		(20 "In9.Cu" signal "VCC1")
		(22 "In10.Cu" signal "GND4")
		(24 "In11.Cu" signal "IN4")
		(26 "In12.Cu" signal "GND5")
		(28 "In13.Cu" signal "IN5")
		(30 "In14.Cu" signal "GND6")
		(32 "In15.Cu" signal "IN6")
		(34 "In16.Cu" signal "GND7")
		(2 "B.Cu" signal "BOTTOM")
		(9 "F.Adhes" user "F.Adhesive")
		(11 "B.Adhes" user "B.Adhesive")
		(13 "F.Paste" user "Package Geometry/Pastemask Top")
		(15 "B.Paste" user "Package Geometry/Pastemask Bottom")
		(5 "F.SilkS" user "Ref Des/Silkscreen Top")
		(7 "B.SilkS" user "Ref Des/Silkscreen Bottom")
		(1 "F.Mask" user "Board Geometry/Soldermask Top")
		(3 "B.Mask" user "Board Geometry/Soldermask Bottom")
		(17 "Dwgs.User" user "User.Drawings")
		(19 "Cmts.User" user "User.Comments")
		(21 "Eco1.User" user "User.Eco1")
		(23 "Eco2.User" user "User.Eco2")
		(25 "Edge.Cuts" user "Board Geometry/Outline")
		(27 "Margin" user)
		(31 "F.CrtYd" user "Package Geometry/Place Bound Top")
		(29 "B.CrtYd" user "Package Geometry/Place Bound Bottom")
		(35 "F.Fab" user "Ref Des/Assembly Top")
		(33 "B.Fab" user "Ref Des/Assembly Bottom")
	)
	(footprint ""
		(layer "B.Cu")
		(at 373.329454 -258.830064)
		(property "Reference" "C2585"
			(at 0 0 0)
			(layer "B.SilkS")
			(hide yes)
			(effects
				(font
					(size 1.27 1.27)
				)
				(justify mirror)
			)
		)
		(property "Value" ""
			(at 0 0 0)
			(layer "B.Fab")
			(effects
				(font
					(size 1.27 1.27)
				)
				(justify mirror)
			)
		)
		(duplicate_pad_numbers_are_jumpers no)
		(fp_line
			(start -0.7874 -0.4064)
			(end -0.7874 0.4064)
			(stroke
				(width 0.1524)
				(type default)
			)
			(layer "B.SilkS")
		)
		(fp_line
			(start -0.7874 0.4064)
			(end 0.7874 0.4064)
			(stroke
				(width 0.1524)
				(type default)
			)
			(layer "B.SilkS")
		)
		(fp_line
			(start 0.7874 -0.4064)
			(end -0.7874 -0.4064)
			(stroke
				(width 0.1524)
				(type default)
			)
			(layer "B.SilkS")
		)
		(fp_line
			(start 0.7874 0.4064)
			(end 0.7874 -0.4064)
			(stroke
				(width 0.1524)
				(type default)
			)
			(layer "B.SilkS")
		)
		(fp_line
			(start -0.67945 -0.3048)
			(end -0.67945 0.3048)
			(stroke
				(width 0.1)
				(type default)
			)
			(layer "B.Fab")
		)
		(fp_line
			(start -0.67945 0.3048)
			(end -0.120396 0.3048)
			(stroke
				(width 0.1)
				(type default)
			)
			(layer "B.Fab")
		)
		(fp_line
			(start -0.12065 -0.3048)
			(end -0.67945 -0.3048)
			(stroke
				(width 0.1)
				(type default)
			)
			(layer "B.Fab")
		)
		(fp_line
			(start -0.12065 -0.2794)
			(end -0.12065 -0.3048)
			(stroke
				(width 0.1)
				(type default)
			)
			(layer "B.Fab")
		)
		(fp_line
			(start -0.120396 0.2794)
			(end 0.12065 0.2794)
			(stroke
				(width 0.1)
				(type default)
			)
			(layer "B.Fab")
		)
		(fp_line
			(start -0.120396 0.3048)
			(end -0.120396 0.2794)
			(stroke
				(width 0.1)
				(type default)
			)
			(layer "B.Fab")
		)
		(fp_line
			(start 0.12065 -0.305054)
			(end 0.12065 -0.2794)
			(stroke
				(width 0.1)
				(type default)
			)
			(layer "B.Fab")
		)
		(fp_line
			(start 0.12065 -0.2794)
			(end -0.12065 -0.2794)
			(stroke
				(width 0.1)
				(type default)
			)
			(layer "B.Fab")
		)
		(fp_line
			(start 0.12065 0.2794)
			(end 0.12065 0.3048)
			(stroke
				(width 0.1)
				(type default)
			)
			(layer "B.Fab")
		)
		(fp_line
			(start 0.12065 0.3048)
			(end 0.67945 0.3048)
			(stroke
				(width 0.1)
				(type default)
			)
			(layer "B.Fab")
		)
		(fp_line
			(start 0.67945 -0.305054)
			(end 0.12065 -0.305054)
			(stroke
				(width 0.1)
				(type default)
			)
			(layer "B.Fab")
		)
		(fp_line
			(start 0.67945 0.3048)
			(end 0.67945 -0.305054)
			(stroke
				(width 0.1)
				(type default)
			)
			(layer "B.Fab")
		)
		(pad "1" smd circle
			(at 0.40005 0 180)
			(size 0 0)
			(layers "B.Cu" "B.Mask" "B.Paste")
			(net "PVDDCR_SOC_P0")
		)
		(pad "2" smd circle
			(at -0.40005 0 180)
			(size 0 0)
			(layers "B.Cu" "B.Mask" "B.Paste")
			(net "GND")
		)
	)
	(footprint ""
		(layer "B.Cu")
		(at 165.006274 -386.766562 90)
		(property "Reference" "C382"
			(at 0 0 90)
			(layer "B.SilkS")
			(hide yes)
			(effects
				(font
					(size 1.27 1.27)
				)
				(justify mirror)
			)
		)
		(property "Value" ""
			(at 0 0 90)
			(layer "B.Fab")
			(effects
				(font
					(size 1.27 1.27)
				)
				(justify mirror)
			)
		)
		(duplicate_pad_numbers_are_jumpers no)
		(fp_line
			(start 0.299974 -0.150114)
			(end -0.299974 -0.150114)
			(stroke
				(width 0.1)
				(type default)
			)
			(layer "B.Fab")
		)
		(fp_line
			(start -0.299974 -0.150114)
			(end -0.299974 0.150114)
			(stroke
				(width 0.1)
				(type default)
			)
			(layer "B.Fab")
		)
		(fp_line
			(start 0.299974 0.150114)
			(end 0.299974 -0.150114)
			(stroke
				(width 0.1)
				(type default)
			)
			(layer "B.Fab")
		)
		(fp_line
			(start -0.299974 0.150114)
			(end 0.299974 0.150114)
			(stroke
				(width 0.1)
				(type default)
			)
			(layer "B.Fab")
		)
		(pad "1" smd rect
			(at 0.2667 0 270)
			(size 0.3048 0.381)
			(layers "B.Cu" "B.Mask" "B.Paste")
			(net "P0V9_CPU1_RT2_2A")
		)
		(pad "2" smd rect
			(at -0.2667 0 270)
			(size 0.3048 0.381)
			(layers "B.Cu" "B.Mask" "B.Paste")
			(net "GND")
		)
	)
	(footprint ""
		(layer "B.Cu")
		(at 130.104642 -72.39254)
		(property "Reference" "PC6026"
			(at 0 0 0)
			(layer "B.SilkS")
			(hide yes)
			(effects
				(font
					(size 1.27 1.27)
				)
				(justify mirror)
			)
		)
		(property "Value" ""
			(at 0 0 0)
			(layer "B.Fab")
			(effects
				(font
					(size 1.27 1.27)
				)
				(justify mirror)
			)
		)
		(duplicate_pad_numbers_are_jumpers no)
		(fp_line
			(start -1.524 -0.762)
			(end -1.524 0.762)
			(stroke
				(width 0.1524)
				(type default)
			)
			(layer "B.SilkS")
		)
		(fp_line
			(start -1.524 0.762)
			(end 1.524 0.762)
			(stroke
				(width 0.1524)
				(type default)
			)
			(layer "B.SilkS")
		)
		(fp_line
			(start 1.524 -0.762)
			(end -1.524 -0.762)
			(stroke
				(width 0.1524)
				(type default)
			)
			(layer "B.SilkS")
		)
		(fp_line
			(start 1.524 0.762)
			(end 1.524 -0.762)
			(stroke
				(width 0.1524)
				(type default)
			)
			(layer "B.SilkS")
		)
		(fp_line
			(start -1.1049 -0.724916)
			(end 1.1049 -0.724916)
			(stroke
				(width 0.1)
				(type default)
			)
			(layer "B.Fab")
		)
		(fp_line
			(start -1.1049 0.724916)
			(end -1.1049 -0.724916)
			(stroke
				(width 0.1)
				(type default)
			)
			(layer "B.Fab")
		)
		(fp_line
			(start 1.1049 -0.724916)
			(end 1.1049 0.724916)
			(stroke
				(width 0.1)
				(type default)
			)
			(layer "B.Fab")
		)
		(fp_line
			(start 1.1049 0.724916)
			(end -1.1049 0.724916)
			(stroke
				(width 0.1)
				(type default)
			)
			(layer "B.Fab")
		)
		(pad "1" smd rect
			(at 0.889 0)
			(size 1.016 1.27)
			(layers "B.Cu" "B.Mask" "B.Paste")
			(net "P1V2_AUX")
		)
		(pad "2" smd rect
			(at -0.889 0)
			(size 1.016 1.27)
			(layers "B.Cu" "B.Mask" "B.Paste")
			(net "GND")
		)
	)
)
